(kicad_pcb
	(version 20260206)
	(generator "pcbnew")
	(generator_version "10.0")
	(general
		(thickness 1.6)
		(legacy_teardrops no)
	)
	(paper "A4")
	(title_block
		(title "01162023_DA0F0TEBIF0_F0T_Expander_BD_F_brd_V02_OCP.brd")
		(comment 1 "Grand Teton / footprints 4879-4886 of 9728")
	)
	(layers
		(0 "F.Cu" signal "TOP")
		(4 "In1.Cu" signal "GND")
		(6 "In2.Cu" signal "VCC")
		(8 "In3.Cu" signal "VCC1")
		(10 "In4.Cu" signal "GND1")
		(12 "In5.Cu" signal "IN1")
		(14 "In6.Cu" signal "GND2")
		(16 "In7.Cu" signal "IN2")
		(18 "In8.Cu" signal "GND3")
		(20 "In9.Cu" signal "IN3")
		(22 "In10.Cu" signal "GND4")
		(24 "In11.Cu" signal "IN4")
		(26 "In12.Cu" signal "GND5")
		(28 "In13.Cu" signal "IN5")
		(30 "In14.Cu" signal "GND6")
		(32 "In15.Cu" signal "IN6")
		(34 "In16.Cu" signal "GND7")
		(2 "B.Cu" signal "BOTTOM")
		(9 "F.Adhes" user "F.Adhesive")
		(11 "B.Adhes" user "B.Adhesive")
		(13 "F.Paste" user "Package Geometry/Pastemask Top")
		(15 "B.Paste" user "Package Geometry/Pastemask Bottom")
		(5 "F.SilkS" user "Ref Des/Silkscreen Top")
		(7 "B.SilkS" user "Ref Des/Silkscreen Bottom")
		(1 "F.Mask" user "Board Geometry/Soldermask Top")
		(3 "B.Mask" user "Board Geometry/Soldermask Bottom")
		(17 "Dwgs.User" user "User.Drawings")
		(19 "Cmts.User" user "User.Comments")
		(21 "Eco1.User" user "User.Eco1")
		(23 "Eco2.User" user "User.Eco2")
		(25 "Edge.Cuts" user "Board Geometry/Outline")
		(27 "Margin" user)
		(31 "F.CrtYd" user "Package Geometry/Place Bound Top")
		(29 "B.CrtYd" user "Package Geometry/Place Bound Bottom")
		(35 "F.Fab" user "Ref Des/Assembly Top")
		(33 "B.Fab" user "Ref Des/Assembly Bottom")
	)
	(footprint ""
		(layer "F.Cu")
		(at 441.442602 -70.844918 -90)
		(property "Reference" "PD51"
			(at 4.093718 2.173732 90)
			(unlocked yes)
			(layer "F.SilkS")
			(effects
				(font
					(size 0.7874 0.5842)
					(thickness 0.1524)
				)
				(justify left)
			)
		)
		(property "Value" ""
			(at 0 0 270)
			(layer "F.Fab")
			(effects
				(font
					(size 1.27 1.27)
				)
			)
		)
		(duplicate_pad_numbers_are_jumpers no)
		(fp_line
			(start -3.400044 1.459992)
			(end -3.400044 -1.459992)
			(stroke
				(width 0.1524)
				(type default)
			)
			(layer "F.SilkS")
		)
		(fp_line
			(start 4.107942 1.459992)
			(end -3.400044 1.459992)
			(stroke
				(width 0.1524)
				(type default)
			)
			(layer "F.SilkS")
		)
		(fp_line
			(start -3.400044 -1.459992)
			(end 4.107942 -1.459992)
			(stroke
				(width 0.1524)
				(type default)
			)
			(layer "F.SilkS")
		)
		(fp_line
			(start 4.107942 -1.459992)
			(end 4.107942 1.459992)
			(stroke
				(width 0.1524)
				(type default)
			)
			(layer "F.SilkS")
		)
		(fp_poly
			(pts
				(xy 4.107942 -1.459992) (xy 4.107942 1.459992) (xy 3.308096 1.459992) (xy 3.308096 -1.459992)
			)
			(stroke
				(width 0)
				(type default)
			)
			(fill yes)
			(layer "F.SilkS")
		)
		(fp_line
			(start -2.29997 1.459992)
			(end -2.29997 -1.459992)
			(stroke
				(width 0.1)
				(type default)
			)
			(layer "F.Fab")
		)
		(fp_line
			(start 2.29997 1.459992)
			(end -2.29997 1.459992)
			(stroke
				(width 0.1)
				(type default)
			)
			(layer "F.Fab")
		)
		(fp_line
			(start -2.29997 -1.459992)
			(end 2.29997 -1.459992)
			(stroke
				(width 0.1)
				(type default)
			)
			(layer "F.Fab")
		)
		(fp_line
			(start 2.29997 -1.459992)
			(end 2.29997 1.459992)
			(stroke
				(width 0.1)
				(type default)
			)
			(layer "F.Fab")
		)
		(fp_text user "-"
			(at 5.4102 0.29845 90)
			(unlocked yes)
			(layer "F.SilkS")
			(effects
				(font
					(size 1.905 1.4224)
					(thickness 0.1524)
				)
				(justify left)
			)
		)
		(fp_text user "+"
			(at -5.148326 -0.183134 270)
			(unlocked yes)
			(layer "F.SilkS")
			(effects
				(font
					(size 1.905 1.4224)
					(thickness 0.1524)
				)
				(justify left)
			)
		)
		(fp_text user "-"
			(at 5.4102 0.29845 90)
			(unlocked yes)
			(layer "F.Fab")
			(effects
				(font
					(size 1.905 1.4224)
					(thickness 0.1524)
				)
				(justify left)
			)
		)
		(fp_text user "+"
			(at -4.7752 -0.12065 270)
			(unlocked yes)
			(layer "F.Fab")
			(effects
				(font
					(size 1.905 1.4224)
					(thickness 0.1524)
				)
				(justify left)
			)
		)
		(pad "A" smd rect
			(at -1.999996 0)
			(size 1.7018 2.5146)
			(layers "F.Cu" "F.Mask" "F.Paste")
			(net "GND")
		)
		(pad "C" smd rect
			(at 1.999996 0)
			(size 1.7018 2.5146)
			(layers "F.Cu" "F.Mask" "F.Paste")
			(net "P12V_SSD15_R")
		)
	)
	(footprint ""
		(layer "F.Cu")
		(at 198.76135 -121.391172 180)
		(property "Reference" "C240"
			(at 0 0 180)
			(layer "F.SilkS")
			(hide yes)
			(effects
				(font
					(size 1.27 1.27)
				)
			)
		)
		(property "Value" ""
			(at 0 0 180)
			(layer "F.Fab")
			(effects
				(font
					(size 1.27 1.27)
				)
			)
		)
		(duplicate_pad_numbers_are_jumpers no)
		(fp_line
			(start 0.299974 0.150114)
			(end -0.299974 0.150114)
			(stroke
				(width 0.1)
				(type default)
			)
			(layer "F.Fab")
		)
		(fp_line
			(start 0.299974 -0.150114)
			(end 0.299974 0.150114)
			(stroke
				(width 0.1)
				(type default)
			)
			(layer "F.Fab")
		)
		(fp_line
			(start -0.299974 0.150114)
			(end -0.299974 -0.150114)
			(stroke
				(width 0.1)
				(type default)
			)
			(layer "F.Fab")
		)
		(fp_line
			(start -0.299974 -0.150114)
			(end 0.299974 -0.150114)
			(stroke
				(width 0.1)
				(type default)
			)
			(layer "F.Fab")
		)
		(pad "1" smd rect
			(at -0.2667 0 180)
			(size 0.3048 0.381)
			(layers "F.Cu" "F.Mask" "F.Paste")
			(net "P5E_PEX1_STN0_TX_DP<1>")
		)
		(pad "2" smd rect
			(at 0.2667 0 180)
			(size 0.3048 0.381)
			(layers "F.Cu" "F.Mask" "F.Paste")
			(net "P5E_PEX1_STN0_TX_C_DP<1>")
		)
	)
	(footprint ""
		(layer "F.Cu")
		(at 28.633928 -356.244906 90)
		(property "Reference" "C181"
			(at 0 0 90)
			(layer "F.SilkS")
			(hide yes)
			(effects
				(font
					(size 1.27 1.27)
				)
			)
		)
		(property "Value" ""
			(at 0 0 90)
			(layer "F.Fab")
			(effects
				(font
					(size 1.27 1.27)
				)
			)
		)
		(duplicate_pad_numbers_are_jumpers no)
		(fp_line
			(start 0.299974 -0.150114)
			(end 0.299974 0.150114)
			(stroke
				(width 0.1)
				(type default)
			)
			(layer "F.Fab")
		)
		(fp_line
			(start -0.299974 -0.150114)
			(end 0.299974 -0.150114)
			(stroke
				(width 0.1)
				(type default)
			)
			(layer "F.Fab")
		)
		(fp_line
			(start 0.299974 0.150114)
			(end -0.299974 0.150114)
			(stroke
				(width 0.1)
				(type default)
			)
			(layer "F.Fab")
		)
		(fp_line
			(start -0.299974 0.150114)
			(end -0.299974 -0.150114)
			(stroke
				(width 0.1)
				(type default)
			)
			(layer "F.Fab")
		)
		(pad "1" smd rect
			(at -0.2667 0 90)
			(size 0.3048 0.381)
			(layers "F.Cu" "F.Mask" "F.Paste")
			(net "P5E_PEX0_STN7_TX_DP<117>")
		)
		(pad "2" smd rect
			(at 0.2667 0 90)
			(size 0.3048 0.381)
			(layers "F.Cu" "F.Mask" "F.Paste")
			(net "P5E_PEX0_STN7_TX_C_DP<117>")
		)
	)
	(footprint ""
		(layer "F.Cu")
		(at 419.95471 -22.867366 90)
		(property "Reference" "C3972"
			(at 0 0 90)
			(layer "F.SilkS")
			(hide yes)
			(effects
				(font
					(size 1.27 1.27)
				)
			)
		)
		(property "Value" ""
			(at 0 0 90)
			(layer "F.Fab")
			(effects
				(font
					(size 1.27 1.27)
				)
			)
		)
		(duplicate_pad_numbers_are_jumpers no)
		(fp_line
			(start 0.7874 -0.4064)
			(end 0.7874 0.4064)
			(stroke
				(width 0.1524)
				(type default)
			)
			(layer "F.SilkS")
		)
		(fp_line
			(start -0.7874 -0.4064)
			(end 0.7874 -0.4064)
			(stroke
				(width 0.1524)
				(type default)
			)
			(layer "F.SilkS")
		)
		(fp_line
			(start 0.7874 0.4064)
			(end -0.7874 0.4064)
			(stroke
				(width 0.1524)
				(type default)
			)
			(layer "F.SilkS")
		)
		(fp_line
			(start -0.7874 0.4064)
			(end -0.7874 -0.4064)
			(stroke
				(width 0.1524)
				(type default)
			)
			(layer "F.SilkS")
		)
		(fp_line
			(start -0.12065 -0.305054)
			(end -0.12065 -0.2794)
			(stroke
				(width 0.1)
				(type default)
			)
			(layer "F.Fab")
		)
		(fp_line
			(start -0.67945 -0.305054)
			(end -0.12065 -0.305054)
			(stroke
				(width 0.1)
				(type default)
			)
			(layer "F.Fab")
		)
		(fp_line
			(start 0.67945 -0.3048)
			(end 0.67945 0.3048)
			(stroke
				(width 0.1)
				(type default)
			)
			(layer "F.Fab")
		)
		(fp_line
			(start 0.12065 -0.3048)
			(end 0.67945 -0.3048)
			(stroke
				(width 0.1)
				(type default)
			)
			(layer "F.Fab")
		)
		(fp_line
			(start 0.12065 -0.2794)
			(end 0.12065 -0.3048)
			(stroke
				(width 0.1)
				(type default)
			)
			(layer "F.Fab")
		)
		(fp_line
			(start -0.12065 -0.2794)
			(end 0.12065 -0.2794)
			(stroke
				(width 0.1)
				(type default)
			)
			(layer "F.Fab")
		)
		(fp_line
			(start 0.120396 0.2794)
			(end -0.12065 0.2794)
			(stroke
				(width 0.1)
				(type default)
			)
			(layer "F.Fab")
		)
		(fp_line
			(start -0.12065 0.2794)
			(end -0.12065 0.3048)
			(stroke
				(width 0.1)
				(type default)
			)
			(layer "F.Fab")
		)
		(fp_line
			(start 0.67945 0.3048)
			(end 0.120396 0.3048)
			(stroke
				(width 0.1)
				(type default)
			)
			(layer "F.Fab")
		)
		(fp_line
			(start 0.120396 0.3048)
			(end 0.120396 0.2794)
			(stroke
				(width 0.1)
				(type default)
			)
			(layer "F.Fab")
		)
		(fp_line
			(start -0.12065 0.3048)
			(end -0.67945 0.3048)
			(stroke
				(width 0.1)
				(type default)
			)
			(layer "F.Fab")
		)
		(fp_line
			(start -0.67945 0.3048)
			(end -0.67945 -0.305054)
			(stroke
				(width 0.1)
				(type default)
			)
			(layer "F.Fab")
		)
		(pad "1" smd circle
			(at -0.40005 0 90)
			(size 0 0)
			(layers "F.Cu" "F.Mask" "F.Paste")
			(net "P12V_SSD14")
		)
		(pad "2" smd circle
			(at 0.40005 0 90)
			(size 0 0)
			(layers "F.Cu" "F.Mask" "F.Paste")
			(net "GND")
		)
	)
	(footprint ""
		(layer "F.Cu")
		(at 145.999962 -244.298978 180)
		(property "Reference" "R6572"
			(at 0 0 180)
			(layer "F.SilkS")
			(hide yes)
			(effects
				(font
					(size 1.27 1.27)
				)
			)
		)
		(property "Value" ""
			(at 0 0 180)
			(layer "F.Fab")
			(effects
				(font
					(size 1.27 1.27)
				)
			)
		)
		(duplicate_pad_numbers_are_jumpers no)
		(fp_line
			(start 0.7874 0.4064)
			(end -0.7874 0.4064)
			(stroke
				(width 0.1524)
				(type default)
			)
			(layer "F.SilkS")
		)
		(fp_line
			(start 0.7874 -0.4064)
			(end 0.7874 0.4064)
			(stroke
				(width 0.1524)
				(type default)
			)
			(layer "F.SilkS")
		)
		(fp_line
			(start -0.7874 0.4064)
			(end -0.7874 -0.4064)
			(stroke
				(width 0.1524)
				(type default)
			)
			(layer "F.SilkS")
		)
		(fp_line
			(start -0.7874 -0.4064)
			(end 0.7874 -0.4064)
			(stroke
				(width 0.1524)
				(type default)
			)
			(layer "F.SilkS")
		)
		(fp_line
			(start 0.67945 0.3048)
			(end 0.120396 0.3048)
			(stroke
				(width 0.1)
				(type default)
			)
			(layer "F.Fab")
		)
		(fp_line
			(start 0.67945 -0.3048)
			(end 0.67945 0.3048)
			(stroke
				(width 0.1)
				(type default)
			)
			(layer "F.Fab")
		)
		(fp_line
			(start 0.12065 -0.2794)
			(end 0.12065 -0.3048)
			(stroke
				(width 0.1)
				(type default)
			)
			(layer "F.Fab")
		)
		(fp_line
			(start 0.12065 -0.3048)
			(end 0.67945 -0.3048)
			(stroke
				(width 0.1)
				(type default)
			)
			(layer "F.Fab")
		)
		(fp_line
			(start 0.120396 0.3048)
			(end 0.120396 0.2794)
			(stroke
				(width 0.1)
				(type default)
			)
			(layer "F.Fab")
		)
		(fp_line
			(start 0.120396 0.2794)
			(end -0.12065 0.2794)
			(stroke
				(width 0.1)
				(type default)
			)
			(layer "F.Fab")
		)
		(fp_line
			(start -0.12065 0.3048)
			(end -0.67945 0.3048)
			(stroke
				(width 0.1)
				(type default)
			)
			(layer "F.Fab")
		)
		(fp_line
			(start -0.12065 0.2794)
			(end -0.12065 0.3048)
			(stroke
				(width 0.1)
				(type default)
			)
			(layer "F.Fab")
		)
		(fp_line
			(start -0.12065 -0.2794)
			(end 0.12065 -0.2794)
			(stroke
				(width 0.1)
				(type default)
			)
			(layer "F.Fab")
		)
		(fp_line
			(start -0.12065 -0.305054)
			(end -0.12065 -0.2794)
			(stroke
				(width 0.1)
				(type default)
			)
			(layer "F.Fab")
		)
		(fp_line
			(start -0.67945 0.3048)
			(end -0.67945 -0.305054)
			(stroke
				(width 0.1)
				(type default)
			)
			(layer "F.Fab")
		)
		(fp_line
			(start -0.67945 -0.305054)
			(end -0.12065 -0.305054)
			(stroke
				(width 0.1)
				(type default)
			)
			(layer "F.Fab")
		)
		(pad "1" smd circle
			(at -0.40005 0 180)
			(size 0 0)
			(layers "F.Cu" "F.Mask" "F.Paste")
			(net "PWR_EN_PEX_R")
		)
		(pad "2" smd circle
			(at 0.40005 0 180)
			(size 0 0)
			(layers "F.Cu" "F.Mask" "F.Paste")
			(net "PEX1_P1V8_PLL_EN")
		)
	)
	(footprint ""
		(layer "F.Cu")
		(at 325.82104 -102.880414 90)
		(property "Reference" "C622"
			(at 0 0 90)
			(layer "F.SilkS")
			(hide yes)
			(effects
				(font
					(size 1.27 1.27)
				)
			)
		)
		(property "Value" ""
			(at 0 0 90)
			(layer "F.Fab")
			(effects
				(font
					(size 1.27 1.27)
				)
			)
		)
		(duplicate_pad_numbers_are_jumpers no)
		(fp_line
			(start 0.7874 -0.4064)
			(end 0.7874 0.4064)
			(stroke
				(width 0.1524)
				(type default)
			)
			(layer "F.SilkS")
		)
		(fp_line
			(start -0.7874 -0.4064)
			(end 0.7874 -0.4064)
			(stroke
				(width 0.1524)
				(type default)
			)
			(layer "F.SilkS")
		)
		(fp_line
			(start 0.7874 0.4064)
			(end -0.7874 0.4064)
			(stroke
				(width 0.1524)
				(type default)
			)
			(layer "F.SilkS")
		)
		(fp_line
			(start -0.7874 0.4064)
			(end -0.7874 -0.4064)
			(stroke
				(width 0.1524)
				(type default)
			)
			(layer "F.SilkS")
		)
		(fp_line
			(start -0.12065 -0.305054)
			(end -0.12065 -0.2794)
			(stroke
				(width 0.1)
				(type default)
			)
			(layer "F.Fab")
		)
		(fp_line
			(start -0.67945 -0.305054)
			(end -0.12065 -0.305054)
			(stroke
				(width 0.1)
				(type default)
			)
			(layer "F.Fab")
		)
		(fp_line
			(start 0.67945 -0.3048)
			(end 0.67945 0.3048)
			(stroke
				(width 0.1)
				(type default)
			)
			(layer "F.Fab")
		)
		(fp_line
			(start 0.12065 -0.3048)
			(end 0.67945 -0.3048)
			(stroke
				(width 0.1)
				(type default)
			)
			(layer "F.Fab")
		)
		(fp_line
			(start 0.12065 -0.2794)
			(end 0.12065 -0.3048)
			(stroke
				(width 0.1)
				(type default)
			)
			(layer "F.Fab")
		)
		(fp_line
			(start -0.12065 -0.2794)
			(end 0.12065 -0.2794)
			(stroke
				(width 0.1)
				(type default)
			)
			(layer "F.Fab")
		)
		(fp_line
			(start 0.120396 0.2794)
			(end -0.12065 0.2794)
			(stroke
				(width 0.1)
				(type default)
			)
			(layer "F.Fab")
		)
		(fp_line
			(start -0.12065 0.2794)
			(end -0.12065 0.3048)
			(stroke
				(width 0.1)
				(type default)
			)
			(layer "F.Fab")
		)
		(fp_line
			(start 0.67945 0.3048)
			(end 0.120396 0.3048)
			(stroke
				(width 0.1)
				(type default)
			)
			(layer "F.Fab")
		)
		(fp_line
			(start 0.120396 0.3048)
			(end 0.120396 0.2794)
			(stroke
				(width 0.1)
				(type default)
			)
			(layer "F.Fab")
		)
		(fp_line
			(start -0.12065 0.3048)
			(end -0.67945 0.3048)
			(stroke
				(width 0.1)
				(type default)
			)
			(layer "F.Fab")
		)
		(fp_line
			(start -0.67945 0.3048)
			(end -0.67945 -0.305054)
			(stroke
				(width 0.1)
				(type default)
			)
			(layer "F.Fab")
		)
		(pad "1" smd circle
			(at -0.40005 0 90)
			(size 0 0)
			(layers "F.Cu" "F.Mask" "F.Paste")
			(net "P3V3_AUX")
		)
		(pad "2" smd circle
			(at 0.40005 0 90)
			(size 0 0)
			(layers "F.Cu" "F.Mask" "F.Paste")
			(net "GND")
		)
	)
	(footprint ""
		(layer "F.Cu")
		(at 226.031298 -86.750398)
		(property "Reference" "R4110"
			(at 0 0 0)
			(layer "F.SilkS")
			(hide yes)
			(effects
				(font
					(size 1.27 1.27)
				)
			)
		)
		(property "Value" ""
			(at 0 0 0)
			(layer "F.Fab")
			(effects
				(font
					(size 1.27 1.27)
				)
			)
		)
		(duplicate_pad_numbers_are_jumpers no)
		(fp_line
			(start -0.7874 -0.4064)
			(end 0.7874 -0.4064)
			(stroke
				(width 0.1524)
				(type default)
			)
			(layer "F.SilkS")
		)
		(fp_line
			(start -0.7874 0.4064)
			(end -0.7874 -0.4064)
			(stroke
				(width 0.1524)
				(type default)
			)
			(layer "F.SilkS")
		)
		(fp_line
			(start 0.7874 -0.4064)
			(end 0.7874 0.4064)
			(stroke
				(width 0.1524)
				(type default)
			)
			(layer "F.SilkS")
		)
		(fp_line
			(start 0.7874 0.4064)
			(end -0.7874 0.4064)
			(stroke
				(width 0.1524)
				(type default)
			)
			(layer "F.SilkS")
		)
		(fp_line
			(start -0.67945 -0.305054)
			(end -0.12065 -0.305054)
			(stroke
				(width 0.1)
				(type default)
			)
			(layer "F.Fab")
		)
		(fp_line
			(start -0.67945 0.3048)
			(end -0.67945 -0.305054)
			(stroke
				(width 0.1)
				(type default)
			)
			(layer "F.Fab")
		)
		(fp_line
			(start -0.12065 -0.305054)
			(end -0.12065 -0.2794)
			(stroke
				(width 0.1)
				(type default)
			)
			(layer "F.Fab")
		)
		(fp_line
			(start -0.12065 -0.2794)
			(end 0.12065 -0.2794)
			(stroke
				(width 0.1)
				(type default)
			)
			(layer "F.Fab")
		)
		(fp_line
			(start -0.12065 0.2794)
			(end -0.12065 0.3048)
			(stroke
				(width 0.1)
				(type default)
			)
			(layer "F.Fab")
		)
		(fp_line
			(start -0.12065 0.3048)
			(end -0.67945 0.3048)
			(stroke
				(width 0.1)
				(type default)
			)
			(layer "F.Fab")
		)
		(fp_line
			(start 0.120396 0.2794)
			(end -0.12065 0.2794)
			(stroke
				(width 0.1)
				(type default)
			)
			(layer "F.Fab")
		)
		(fp_line
			(start 0.120396 0.3048)
			(end 0.120396 0.2794)
			(stroke
				(width 0.1)
				(type default)
			)
			(layer "F.Fab")
		)
		(fp_line
			(start 0.12065 -0.3048)
			(end 0.67945 -0.3048)
			(stroke
				(width 0.1)
				(type default)
			)
			(layer "F.Fab")
		)
		(fp_line
			(start 0.12065 -0.2794)
			(end 0.12065 -0.3048)
			(stroke
				(width 0.1)
				(type default)
			)
			(layer "F.Fab")
		)
		(fp_line
			(start 0.67945 -0.3048)
			(end 0.67945 0.3048)
			(stroke
				(width 0.1)
				(type default)
			)
			(layer "F.Fab")
		)
		(fp_line
			(start 0.67945 0.3048)
			(end 0.120396 0.3048)
			(stroke
				(width 0.1)
				(type default)
			)
			(layer "F.Fab")
		)
		(pad "1" smd circle
			(at -0.40005 0)
			(size 0 0)
			(layers "F.Cu" "F.Mask" "F.Paste")
			(net "SMB_BIC_I2C6_R_SCL")
		)
		(pad "2" smd circle
			(at 0.40005 0)
			(size 0 0)
			(layers "F.Cu" "F.Mask" "F.Paste")
			(net "SMB_BIC_I2C6_SENEOR_SCL")
		)
	)
	(footprint ""
		(layer "F.Cu")
		(at 191.055752 -350.098614 90)
		(property "Reference" "C375"
			(at 0 0 90)
			(layer "F.SilkS")
			(hide yes)
			(effects
				(font
					(size 1.27 1.27)
				)
			)
		)
		(property "Value" ""
			(at 0 0 90)
			(layer "F.Fab")
			(effects
				(font
					(size 1.27 1.27)
				)
			)
		)
		(duplicate_pad_numbers_are_jumpers no)
		(fp_line
			(start 0.299974 -0.150114)
			(end 0.299974 0.150114)
			(stroke
				(width 0.1)
				(type default)
			)
			(layer "F.Fab")
		)
		(fp_line
			(start -0.299974 -0.150114)
			(end 0.299974 -0.150114)
			(stroke
				(width 0.1)
				(type default)
			)
			(layer "F.Fab")
		)
		(fp_line
			(start 0.299974 0.150114)
			(end -0.299974 0.150114)
			(stroke
				(width 0.1)
				(type default)
			)
			(layer "F.Fab")
		)
		(fp_line
			(start -0.299974 0.150114)
			(end -0.299974 -0.150114)
			(stroke
				(width 0.1)
				(type default)
			)
			(layer "F.Fab")
		)
		(pad "1" smd rect
			(at -0.2667 0 90)
			(size 0.3048 0.381)
			(layers "F.Cu" "F.Mask" "F.Paste")
			(net "P5E_PEX1_STN7_TX_DN<126>")
		)
		(pad "2" smd rect
			(at 0.2667 0 90)
			(size 0.3048 0.381)
			(layers "F.Cu" "F.Mask" "F.Paste")
			(net "P5E_PEX1_STN7_TX_C_DN<126>")
		)
	)
)
